(kicad_pcb
	(version 20260206)
	(generator "pcbnew")
	(generator_version "10.0")
	(general
		(thickness 1.6)
		(legacy_teardrops no)
	)
	(paper "A4")
	(title_block
		(title "04192023_DAF0TMB3IC0_F0TG_MB_C_brd_V02_OCP.brd")
		(comment 1 "Grand Teton / footprints 1324-1331 of 8354")
	)
	(layers
		(0 "F.Cu" signal "TOP")
		(4 "In1.Cu" signal "GND")
		(6 "In2.Cu" signal "IN1")
		(8 "In3.Cu" signal "GND1")
		(10 "In4.Cu" signal "IN2")
		(12 "In5.Cu" signal "GND2")
		(14 "In6.Cu" signal "IN3")
		(16 "In7.Cu" signal "GND3")
		(18 "In8.Cu" signal "VCC")
		(20 "In9.Cu" signal "VCC1")
		(22 "In10.Cu" signal "GND4")
		(24 "In11.Cu" signal "IN4")
		(26 "In12.Cu" signal "GND5")
		(28 "In13.Cu" signal "IN5")
		(30 "In14.Cu" signal "GND6")
		(32 "In15.Cu" signal "IN6")
		(34 "In16.Cu" signal "GND7")
		(2 "B.Cu" signal "BOTTOM")
		(9 "F.Adhes" user "F.Adhesive")
		(11 "B.Adhes" user "B.Adhesive")
		(13 "F.Paste" user "Package Geometry/Pastemask Top")
		(15 "B.Paste" user "Package Geometry/Pastemask Bottom")
		(5 "F.SilkS" user "Ref Des/Silkscreen Top")
		(7 "B.SilkS" user "Ref Des/Silkscreen Bottom")
		(1 "F.Mask" user "Board Geometry/Soldermask Top")
		(3 "B.Mask" user "Board Geometry/Soldermask Bottom")
		(17 "Dwgs.User" user "User.Drawings")
		(19 "Cmts.User" user "User.Comments")
		(21 "Eco1.User" user "User.Eco1")
		(23 "Eco2.User" user "User.Eco2")
		(25 "Edge.Cuts" user "Board Geometry/Outline")
		(27 "Margin" user)
		(31 "F.CrtYd" user "Package Geometry/Place Bound Top")
		(29 "B.CrtYd" user "Package Geometry/Place Bound Bottom")
		(35 "F.Fab" user "Ref Des/Assembly Top")
		(33 "B.Fab" user "Ref Des/Assembly Bottom")
	)
	(footprint ""
		(layer "F.Cu")
		(at 178.689 -408.559)
		(property "Reference" "R3933"
			(at 0 0 0)
			(layer "F.SilkS")
			(hide yes)
			(effects
				(font
					(size 1.27 1.27)
				)
			)
		)
		(property "Value" ""
			(at 0 0 0)
			(layer "F.Fab")
			(effects
				(font
					(size 1.27 1.27)
				)
			)
		)
		(duplicate_pad_numbers_are_jumpers no)
		(fp_line
			(start -0.7874 -0.4064)
			(end 0.7874 -0.4064)
			(stroke
				(width 0.1524)
				(type default)
			)
			(layer "F.SilkS")
		)
		(fp_line
			(start -0.7874 0.4064)
			(end -0.7874 -0.4064)
			(stroke
				(width 0.1524)
				(type default)
			)
			(layer "F.SilkS")
		)
		(fp_line
			(start 0.7874 -0.4064)
			(end 0.7874 0.4064)
			(stroke
				(width 0.1524)
				(type default)
			)
			(layer "F.SilkS")
		)
		(fp_line
			(start 0.7874 0.4064)
			(end -0.7874 0.4064)
			(stroke
				(width 0.1524)
				(type default)
			)
			(layer "F.SilkS")
		)
		(fp_line
			(start -0.67945 -0.305054)
			(end -0.12065 -0.305054)
			(stroke
				(width 0.1)
				(type default)
			)
			(layer "F.Fab")
		)
		(fp_line
			(start -0.67945 0.3048)
			(end -0.67945 -0.305054)
			(stroke
				(width 0.1)
				(type default)
			)
			(layer "F.Fab")
		)
		(fp_line
			(start -0.12065 -0.305054)
			(end -0.12065 -0.2794)
			(stroke
				(width 0.1)
				(type default)
			)
			(layer "F.Fab")
		)
		(fp_line
			(start -0.12065 -0.2794)
			(end 0.12065 -0.2794)
			(stroke
				(width 0.1)
				(type default)
			)
			(layer "F.Fab")
		)
		(fp_line
			(start -0.12065 0.2794)
			(end -0.12065 0.3048)
			(stroke
				(width 0.1)
				(type default)
			)
			(layer "F.Fab")
		)
		(fp_line
			(start -0.12065 0.3048)
			(end -0.67945 0.3048)
			(stroke
				(width 0.1)
				(type default)
			)
			(layer "F.Fab")
		)
		(fp_line
			(start 0.120396 0.2794)
			(end -0.12065 0.2794)
			(stroke
				(width 0.1)
				(type default)
			)
			(layer "F.Fab")
		)
		(fp_line
			(start 0.120396 0.3048)
			(end 0.120396 0.2794)
			(stroke
				(width 0.1)
				(type default)
			)
			(layer "F.Fab")
		)
		(fp_line
			(start 0.12065 -0.3048)
			(end 0.67945 -0.3048)
			(stroke
				(width 0.1)
				(type default)
			)
			(layer "F.Fab")
		)
		(fp_line
			(start 0.12065 -0.2794)
			(end 0.12065 -0.3048)
			(stroke
				(width 0.1)
				(type default)
			)
			(layer "F.Fab")
		)
		(fp_line
			(start 0.67945 -0.3048)
			(end 0.67945 0.3048)
			(stroke
				(width 0.1)
				(type default)
			)
			(layer "F.Fab")
		)
		(fp_line
			(start 0.67945 0.3048)
			(end 0.120396 0.3048)
			(stroke
				(width 0.1)
				(type default)
			)
			(layer "F.Fab")
		)
		(pad "1" smd circle
			(at -0.40005 0)
			(size 0 0)
			(layers "F.Cu" "F.Mask" "F.Paste")
			(net "P12V_AUX")
		)
		(pad "2" smd circle
			(at 0.40005 0)
			(size 0 0)
			(layers "F.Cu" "F.Mask" "F.Paste")
			(net "MB0_P12V_STBY_PWRGD")
		)
	)
	(footprint ""
		(layer "F.Cu")
		(at 451.573392 -52.84851 90)
		(property "Reference" "PC570"
			(at 0 0 90)
			(layer "F.SilkS")
			(hide yes)
			(effects
				(font
					(size 1.27 1.27)
				)
			)
		)
		(property "Value" ""
			(at 0 0 90)
			(layer "F.Fab")
			(effects
				(font
					(size 1.27 1.27)
				)
			)
		)
		(duplicate_pad_numbers_are_jumpers no)
		(fp_line
			(start 1.524 -0.762)
			(end 1.524 0.762)
			(stroke
				(width 0.1524)
				(type default)
			)
			(layer "F.SilkS")
		)
		(fp_line
			(start -1.524 -0.762)
			(end 1.524 -0.762)
			(stroke
				(width 0.1524)
				(type default)
			)
			(layer "F.SilkS")
		)
		(fp_line
			(start 1.524 0.762)
			(end -1.524 0.762)
			(stroke
				(width 0.1524)
				(type default)
			)
			(layer "F.SilkS")
		)
		(fp_line
			(start -1.524 0.762)
			(end -1.524 -0.762)
			(stroke
				(width 0.1524)
				(type default)
			)
			(layer "F.SilkS")
		)
		(fp_line
			(start 1.1049 -0.724916)
			(end -1.1049 -0.724916)
			(stroke
				(width 0.1)
				(type default)
			)
			(layer "F.Fab")
		)
		(fp_line
			(start -1.1049 -0.724916)
			(end -1.1049 0.724916)
			(stroke
				(width 0.1)
				(type default)
			)
			(layer "F.Fab")
		)
		(fp_line
			(start 1.1049 0.724916)
			(end 1.1049 -0.724916)
			(stroke
				(width 0.1)
				(type default)
			)
			(layer "F.Fab")
		)
		(fp_line
			(start -1.1049 0.724916)
			(end 1.1049 0.724916)
			(stroke
				(width 0.1)
				(type default)
			)
			(layer "F.Fab")
		)
		(pad "1" smd rect
			(at -0.889 0 270)
			(size 1.016 1.27)
			(layers "F.Cu" "F.Mask" "F.Paste")
			(net "SW_P3V3_AUX_FLT")
		)
		(pad "2" smd rect
			(at 0.889 0 270)
			(size 1.016 1.27)
			(layers "F.Cu" "F.Mask" "F.Paste")
			(net "GND")
		)
	)
	(footprint ""
		(layer "F.Cu")
		(at 267.701014 -380.66853)
		(property "Reference" "PR2530"
			(at 0 0 0)
			(layer "F.SilkS")
			(hide yes)
			(effects
				(font
					(size 1.27 1.27)
				)
			)
		)
		(property "Value" ""
			(at 0 0 0)
			(layer "F.Fab")
			(effects
				(font
					(size 1.27 1.27)
				)
			)
		)
		(duplicate_pad_numbers_are_jumpers no)
		(fp_line
			(start -0.7874 -0.4064)
			(end 0.7874 -0.4064)
			(stroke
				(width 0.1524)
				(type default)
			)
			(layer "F.SilkS")
		)
		(fp_line
			(start -0.7874 0.4064)
			(end -0.7874 -0.4064)
			(stroke
				(width 0.1524)
				(type default)
			)
			(layer "F.SilkS")
		)
		(fp_line
			(start 0.7874 -0.4064)
			(end 0.7874 0.4064)
			(stroke
				(width 0.1524)
				(type default)
			)
			(layer "F.SilkS")
		)
		(fp_line
			(start 0.7874 0.4064)
			(end -0.7874 0.4064)
			(stroke
				(width 0.1524)
				(type default)
			)
			(layer "F.SilkS")
		)
		(fp_line
			(start -0.67945 -0.305054)
			(end -0.12065 -0.305054)
			(stroke
				(width 0.1)
				(type default)
			)
			(layer "F.Fab")
		)
		(fp_line
			(start -0.67945 0.3048)
			(end -0.67945 -0.305054)
			(stroke
				(width 0.1)
				(type default)
			)
			(layer "F.Fab")
		)
		(fp_line
			(start -0.12065 -0.305054)
			(end -0.12065 -0.2794)
			(stroke
				(width 0.1)
				(type default)
			)
			(layer "F.Fab")
		)
		(fp_line
			(start -0.12065 -0.2794)
			(end 0.12065 -0.2794)
			(stroke
				(width 0.1)
				(type default)
			)
			(layer "F.Fab")
		)
		(fp_line
			(start -0.12065 0.2794)
			(end -0.12065 0.3048)
			(stroke
				(width 0.1)
				(type default)
			)
			(layer "F.Fab")
		)
		(fp_line
			(start -0.12065 0.3048)
			(end -0.67945 0.3048)
			(stroke
				(width 0.1)
				(type default)
			)
			(layer "F.Fab")
		)
		(fp_line
			(start 0.120396 0.2794)
			(end -0.12065 0.2794)
			(stroke
				(width 0.1)
				(type default)
			)
			(layer "F.Fab")
		)
		(fp_line
			(start 0.120396 0.3048)
			(end 0.120396 0.2794)
			(stroke
				(width 0.1)
				(type default)
			)
			(layer "F.Fab")
		)
		(fp_line
			(start 0.12065 -0.3048)
			(end 0.67945 -0.3048)
			(stroke
				(width 0.1)
				(type default)
			)
			(layer "F.Fab")
		)
		(fp_line
			(start 0.12065 -0.2794)
			(end 0.12065 -0.3048)
			(stroke
				(width 0.1)
				(type default)
			)
			(layer "F.Fab")
		)
		(fp_line
			(start 0.67945 -0.3048)
			(end 0.67945 0.3048)
			(stroke
				(width 0.1)
				(type default)
			)
			(layer "F.Fab")
		)
		(fp_line
			(start 0.67945 0.3048)
			(end 0.120396 0.3048)
			(stroke
				(width 0.1)
				(type default)
			)
			(layer "F.Fab")
		)
		(pad "1" smd circle
			(at -0.40005 0)
			(size 0 0)
			(layers "F.Cu" "F.Mask" "F.Paste")
			(net "P12V_HSC_GATE_G3")
		)
		(pad "2" smd circle
			(at 0.40005 0)
			(size 0 0)
			(layers "F.Cu" "F.Mask" "F.Paste")
			(net "P12V_HSC_GATE2")
		)
	)
	(footprint ""
		(layer "F.Cu")
		(at 82.378804 -408.517344 -90)
		(property "Reference" "C6651"
			(at 0 0 270)
			(layer "F.SilkS")
			(hide yes)
			(effects
				(font
					(size 1.27 1.27)
				)
			)
		)
		(property "Value" ""
			(at 0 0 270)
			(layer "F.Fab")
			(effects
				(font
					(size 1.27 1.27)
				)
			)
		)
		(duplicate_pad_numbers_are_jumpers no)
		(fp_line
			(start -0.299974 0.150114)
			(end -0.299974 -0.150114)
			(stroke
				(width 0.1)
				(type default)
			)
			(layer "F.Fab")
		)
		(fp_line
			(start 0.299974 0.150114)
			(end -0.299974 0.150114)
			(stroke
				(width 0.1)
				(type default)
			)
			(layer "F.Fab")
		)
		(fp_line
			(start -0.299974 -0.150114)
			(end 0.299974 -0.150114)
			(stroke
				(width 0.1)
				(type default)
			)
			(layer "F.Fab")
		)
		(fp_line
			(start 0.299974 -0.150114)
			(end 0.299974 0.150114)
			(stroke
				(width 0.1)
				(type default)
			)
			(layer "F.Fab")
		)
		(pad "1" smd rect
			(at -0.2667 0 270)
			(size 0.3048 0.381)
			(layers "F.Cu" "F.Mask" "F.Paste")
			(net "P5E_CPU1_P0_TX_BUF_C_DP<11>")
		)
		(pad "2" smd rect
			(at 0.2667 0 270)
			(size 0.3048 0.381)
			(layers "F.Cu" "F.Mask" "F.Paste")
			(net "P5E_CPU1_P0_TX_BUF_DP<11>")
		)
	)
	(footprint ""
		(layer "F.Cu")
		(at 15.288006 -104.73563 90)
		(property "Reference" "R3651"
			(at 0 0 90)
			(layer "F.SilkS")
			(hide yes)
			(effects
				(font
					(size 1.27 1.27)
				)
			)
		)
		(property "Value" ""
			(at 0 0 90)
			(layer "F.Fab")
			(effects
				(font
					(size 1.27 1.27)
				)
			)
		)
		(duplicate_pad_numbers_are_jumpers no)
		(fp_line
			(start 0.7874 -0.4064)
			(end 0.7874 0.4064)
			(stroke
				(width 0.1524)
				(type default)
			)
			(layer "F.SilkS")
		)
		(fp_line
			(start -0.7874 -0.4064)
			(end 0.7874 -0.4064)
			(stroke
				(width 0.1524)
				(type default)
			)
			(layer "F.SilkS")
		)
		(fp_line
			(start 0.7874 0.4064)
			(end -0.7874 0.4064)
			(stroke
				(width 0.1524)
				(type default)
			)
			(layer "F.SilkS")
		)
		(fp_line
			(start -0.7874 0.4064)
			(end -0.7874 -0.4064)
			(stroke
				(width 0.1524)
				(type default)
			)
			(layer "F.SilkS")
		)
		(fp_line
			(start -0.12065 -0.305054)
			(end -0.12065 -0.2794)
			(stroke
				(width 0.1)
				(type default)
			)
			(layer "F.Fab")
		)
		(fp_line
			(start -0.67945 -0.305054)
			(end -0.12065 -0.305054)
			(stroke
				(width 0.1)
				(type default)
			)
			(layer "F.Fab")
		)
		(fp_line
			(start 0.67945 -0.3048)
			(end 0.67945 0.3048)
			(stroke
				(width 0.1)
				(type default)
			)
			(layer "F.Fab")
		)
		(fp_line
			(start 0.12065 -0.3048)
			(end 0.67945 -0.3048)
			(stroke
				(width 0.1)
				(type default)
			)
			(layer "F.Fab")
		)
		(fp_line
			(start 0.12065 -0.2794)
			(end 0.12065 -0.3048)
			(stroke
				(width 0.1)
				(type default)
			)
			(layer "F.Fab")
		)
		(fp_line
			(start -0.12065 -0.2794)
			(end 0.12065 -0.2794)
			(stroke
				(width 0.1)
				(type default)
			)
			(layer "F.Fab")
		)
		(fp_line
			(start 0.120396 0.2794)
			(end -0.12065 0.2794)
			(stroke
				(width 0.1)
				(type default)
			)
			(layer "F.Fab")
		)
		(fp_line
			(start -0.12065 0.2794)
			(end -0.12065 0.3048)
			(stroke
				(width 0.1)
				(type default)
			)
			(layer "F.Fab")
		)
		(fp_line
			(start 0.67945 0.3048)
			(end 0.120396 0.3048)
			(stroke
				(width 0.1)
				(type default)
			)
			(layer "F.Fab")
		)
		(fp_line
			(start 0.120396 0.3048)
			(end 0.120396 0.2794)
			(stroke
				(width 0.1)
				(type default)
			)
			(layer "F.Fab")
		)
		(fp_line
			(start -0.12065 0.3048)
			(end -0.67945 0.3048)
			(stroke
				(width 0.1)
				(type default)
			)
			(layer "F.Fab")
		)
		(fp_line
			(start -0.67945 0.3048)
			(end -0.67945 -0.305054)
			(stroke
				(width 0.1)
				(type default)
			)
			(layer "F.Fab")
		)
		(pad "1" smd rect
			(at -0.40005 0 270)
			(size 0.4572 0.508)
			(layers "F.Cu" "F.Mask" "F.Paste")
			(net "USB2_P0_R_DP")
		)
		(pad "2" smd rect
			(at 0.40005 0 270)
			(size 0.4572 0.508)
			(layers "F.Cu" "F.Mask" "F.Paste")
			(net "USB2_HOST_BMC_B_DP")
		)
	)
	(footprint ""
		(layer "F.Cu")
		(at 104.1908 -390.652)
		(property "Reference" "R1377"
			(at 0 0 0)
			(layer "F.SilkS")
			(hide yes)
			(effects
				(font
					(size 1.27 1.27)
				)
			)
		)
		(property "Value" ""
			(at 0 0 0)
			(layer "F.Fab")
			(effects
				(font
					(size 1.27 1.27)
				)
			)
		)
		(duplicate_pad_numbers_are_jumpers no)
		(fp_line
			(start -0.32512 -0.175006)
			(end 0.32512 -0.175006)
			(stroke
				(width 0.1)
				(type default)
			)
			(layer "F.Fab")
		)
		(fp_line
			(start -0.32512 0.175006)
			(end -0.32512 -0.175006)
			(stroke
				(width 0.1)
				(type default)
			)
			(layer "F.Fab")
		)
		(fp_line
			(start 0.32512 -0.175006)
			(end 0.32512 0.175006)
			(stroke
				(width 0.1)
				(type default)
			)
			(layer "F.Fab")
		)
		(fp_line
			(start 0.32512 0.175006)
			(end -0.32512 0.175006)
			(stroke
				(width 0.1)
				(type default)
			)
			(layer "F.Fab")
		)
		(pad "1" smd rect
			(at -0.2667 0)
			(size 0.3048 0.381)
			(layers "F.Cu" "F.Mask" "F.Paste")
			(net "P1V8_CPU1_RT_1D")
		)
		(pad "2" smd rect
			(at 0.2667 0 180)
			(size 0.3048 0.381)
			(layers "F.Cu" "F.Mask" "F.Paste")
			(net "RXDET_BYP_RT_CPU1_P1")
		)
	)
	(footprint ""
		(layer "F.Cu")
		(at 99.917504 -119.557038 90)
		(property "Reference" "R6504"
			(at 0 0 90)
			(layer "F.SilkS")
			(hide yes)
			(effects
				(font
					(size 1.27 1.27)
				)
			)
		)
		(property "Value" ""
			(at 0 0 90)
			(layer "F.Fab")
			(effects
				(font
					(size 1.27 1.27)
				)
			)
		)
		(duplicate_pad_numbers_are_jumpers no)
		(fp_line
			(start 0.7874 -0.4064)
			(end 0.7874 0.4064)
			(stroke
				(width 0.1524)
				(type default)
			)
			(layer "F.SilkS")
		)
		(fp_line
			(start -0.7874 -0.4064)
			(end 0.7874 -0.4064)
			(stroke
				(width 0.1524)
				(type default)
			)
			(layer "F.SilkS")
		)
		(fp_line
			(start 0.7874 0.4064)
			(end -0.7874 0.4064)
			(stroke
				(width 0.1524)
				(type default)
			)
			(layer "F.SilkS")
		)
		(fp_line
			(start -0.7874 0.4064)
			(end -0.7874 -0.4064)
			(stroke
				(width 0.1524)
				(type default)
			)
			(layer "F.SilkS")
		)
		(fp_line
			(start -0.12065 -0.305054)
			(end -0.12065 -0.2794)
			(stroke
				(width 0.1)
				(type default)
			)
			(layer "F.Fab")
		)
		(fp_line
			(start -0.67945 -0.305054)
			(end -0.12065 -0.305054)
			(stroke
				(width 0.1)
				(type default)
			)
			(layer "F.Fab")
		)
		(fp_line
			(start 0.67945 -0.3048)
			(end 0.67945 0.3048)
			(stroke
				(width 0.1)
				(type default)
			)
			(layer "F.Fab")
		)
		(fp_line
			(start 0.12065 -0.3048)
			(end 0.67945 -0.3048)
			(stroke
				(width 0.1)
				(type default)
			)
			(layer "F.Fab")
		)
		(fp_line
			(start 0.12065 -0.2794)
			(end 0.12065 -0.3048)
			(stroke
				(width 0.1)
				(type default)
			)
			(layer "F.Fab")
		)
		(fp_line
			(start -0.12065 -0.2794)
			(end 0.12065 -0.2794)
			(stroke
				(width 0.1)
				(type default)
			)
			(layer "F.Fab")
		)
		(fp_line
			(start 0.120396 0.2794)
			(end -0.12065 0.2794)
			(stroke
				(width 0.1)
				(type default)
			)
			(layer "F.Fab")
		)
		(fp_line
			(start -0.12065 0.2794)
			(end -0.12065 0.3048)
			(stroke
				(width 0.1)
				(type default)
			)
			(layer "F.Fab")
		)
		(fp_line
			(start 0.67945 0.3048)
			(end 0.120396 0.3048)
			(stroke
				(width 0.1)
				(type default)
			)
			(layer "F.Fab")
		)
		(fp_line
			(start 0.120396 0.3048)
			(end 0.120396 0.2794)
			(stroke
				(width 0.1)
				(type default)
			)
			(layer "F.Fab")
		)
		(fp_line
			(start -0.12065 0.3048)
			(end -0.67945 0.3048)
			(stroke
				(width 0.1)
				(type default)
			)
			(layer "F.Fab")
		)
		(fp_line
			(start -0.67945 0.3048)
			(end -0.67945 -0.305054)
			(stroke
				(width 0.1)
				(type default)
			)
			(layer "F.Fab")
		)
		(pad "1" smd circle
			(at -0.40005 0 90)
			(size 0 0)
			(layers "F.Cu" "F.Mask" "F.Paste")
			(net "P1V8_AUX")
		)
		(pad "2" smd circle
			(at 0.40005 0 90)
			(size 0 0)
			(layers "F.Cu" "F.Mask" "F.Paste")
			(net "PU_U38_6")
		)
	)
	(footprint ""
		(layer "F.Cu")
		(at 329.360022 -32.953706)
		(property "Reference" "C2042"
			(at 0 0 0)
			(layer "F.SilkS")
			(hide yes)
			(effects
				(font
					(size 1.27 1.27)
				)
			)
		)
		(property "Value" ""
			(at 0 0 0)
			(layer "F.Fab")
			(effects
				(font
					(size 1.27 1.27)
				)
			)
		)
		(duplicate_pad_numbers_are_jumpers no)
		(fp_line
			(start -0.7874 -0.4064)
			(end 0.7874 -0.4064)
			(stroke
				(width 0.1524)
				(type default)
			)
			(layer "F.SilkS")
		)
		(fp_line
			(start -0.7874 0.4064)
			(end -0.7874 -0.4064)
			(stroke
				(width 0.1524)
				(type default)
			)
			(layer "F.SilkS")
		)
		(fp_line
			(start 0.7874 -0.4064)
			(end 0.7874 0.4064)
			(stroke
				(width 0.1524)
				(type default)
			)
			(layer "F.SilkS")
		)
		(fp_line
			(start 0.7874 0.4064)
			(end -0.7874 0.4064)
			(stroke
				(width 0.1524)
				(type default)
			)
			(layer "F.SilkS")
		)
		(fp_line
			(start -0.67945 -0.305054)
			(end -0.12065 -0.305054)
			(stroke
				(width 0.1)
				(type default)
			)
			(layer "F.Fab")
		)
		(fp_line
			(start -0.67945 0.3048)
			(end -0.67945 -0.305054)
			(stroke
				(width 0.1)
				(type default)
			)
			(layer "F.Fab")
		)
		(fp_line
			(start -0.12065 -0.305054)
			(end -0.12065 -0.2794)
			(stroke
				(width 0.1)
				(type default)
			)
			(layer "F.Fab")
		)
		(fp_line
			(start -0.12065 -0.2794)
			(end 0.12065 -0.2794)
			(stroke
				(width 0.1)
				(type default)
			)
			(layer "F.Fab")
		)
		(fp_line
			(start -0.12065 0.2794)
			(end -0.12065 0.3048)
			(stroke
				(width 0.1)
				(type default)
			)
			(layer "F.Fab")
		)
		(fp_line
			(start -0.12065 0.3048)
			(end -0.67945 0.3048)
			(stroke
				(width 0.1)
				(type default)
			)
			(layer "F.Fab")
		)
		(fp_line
			(start 0.120396 0.2794)
			(end -0.12065 0.2794)
			(stroke
				(width 0.1)
				(type default)
			)
			(layer "F.Fab")
		)
		(fp_line
			(start 0.120396 0.3048)
			(end 0.120396 0.2794)
			(stroke
				(width 0.1)
				(type default)
			)
			(layer "F.Fab")
		)
		(fp_line
			(start 0.12065 -0.3048)
			(end 0.67945 -0.3048)
			(stroke
				(width 0.1)
				(type default)
			)
			(layer "F.Fab")
		)
		(fp_line
			(start 0.12065 -0.2794)
			(end 0.12065 -0.3048)
			(stroke
				(width 0.1)
				(type default)
			)
			(layer "F.Fab")
		)
		(fp_line
			(start 0.67945 -0.3048)
			(end 0.67945 0.3048)
			(stroke
				(width 0.1)
				(type default)
			)
			(layer "F.Fab")
		)
		(fp_line
			(start 0.67945 0.3048)
			(end 0.120396 0.3048)
			(stroke
				(width 0.1)
				(type default)
			)
			(layer "F.Fab")
		)
		(pad "1" smd circle
			(at -0.40005 0)
			(size 0 0)
			(layers "F.Cu" "F.Mask" "F.Paste")
			(net "P3V3_AUX_ADC_MAM")
		)
		(pad "2" smd circle
			(at 0.40005 0)
			(size 0 0)
			(layers "F.Cu" "F.Mask" "F.Paste")
			(net "GND")
		)
	)
)
